(kicad_pcb
	(version 20260206)
	(generator "pcbnew")
	(generator_version "10.0")
	(general
		(thickness 1.6)
		(legacy_teardrops no)
	)
	(paper "A4")
	(title_block
		(title "04192023_DAF0TMB3IC0_F0TG_MB_C_brd_V02_OCP.brd")
		(comment 1 "Grand Teton / footprints 1012-1018 of 8354")
	)
	(layers
		(0 "F.Cu" signal "TOP")
		(4 "In1.Cu" signal "GND")
		(6 "In2.Cu" signal "IN1")
		(8 "In3.Cu" signal "GND1")
		(10 "In4.Cu" signal "IN2")
		(12 "In5.Cu" signal "GND2")
		(14 "In6.Cu" signal "IN3")
		(16 "In7.Cu" signal "GND3")
		(18 "In8.Cu" signal "VCC")
		(20 "In9.Cu" signal "VCC1")
		(22 "In10.Cu" signal "GND4")
		(24 "In11.Cu" signal "IN4")
		(26 "In12.Cu" signal "GND5")
		(28 "In13.Cu" signal "IN5")
		(30 "In14.Cu" signal "GND6")
		(32 "In15.Cu" signal "IN6")
		(34 "In16.Cu" signal "GND7")
		(2 "B.Cu" signal "BOTTOM")
		(9 "F.Adhes" user "F.Adhesive")
		(11 "B.Adhes" user "B.Adhesive")
		(13 "F.Paste" user "Package Geometry/Pastemask Top")
		(15 "B.Paste" user "Package Geometry/Pastemask Bottom")
		(5 "F.SilkS" user "Ref Des/Silkscreen Top")
		(7 "B.SilkS" user "Ref Des/Silkscreen Bottom")
		(1 "F.Mask" user "Board Geometry/Soldermask Top")
		(3 "B.Mask" user "Board Geometry/Soldermask Bottom")
		(17 "Dwgs.User" user "User.Drawings")
		(19 "Cmts.User" user "User.Comments")
		(21 "Eco1.User" user "User.Eco1")
		(23 "Eco2.User" user "User.Eco2")
		(25 "Edge.Cuts" user "Board Geometry/Outline")
		(27 "Margin" user)
		(31 "F.CrtYd" user "Package Geometry/Place Bound Top")
		(29 "B.CrtYd" user "Package Geometry/Place Bound Bottom")
		(35 "F.Fab" user "Ref Des/Assembly Top")
		(33 "B.Fab" user "Ref Des/Assembly Bottom")
	)
	(footprint ""
		(layer "F.Cu")
		(at 101.948234 -142.59941 180)
		(property "Reference" "PR157"
			(at 0 0 180)
			(layer "F.SilkS")
			(hide yes)
			(effects
				(font
					(size 1.27 1.27)
				)
			)
		)
		(property "Value" ""
			(at 0 0 180)
			(layer "F.Fab")
			(effects
				(font
					(size 1.27 1.27)
				)
			)
		)
		(duplicate_pad_numbers_are_jumpers no)
		(fp_line
			(start 0.7874 0.4064)
			(end -0.7874 0.4064)
			(stroke
				(width 0.1524)
				(type default)
			)
			(layer "F.SilkS")
		)
		(fp_line
			(start 0.7874 -0.4064)
			(end 0.7874 0.4064)
			(stroke
				(width 0.1524)
				(type default)
			)
			(layer "F.SilkS")
		)
		(fp_line
			(start -0.7874 0.4064)
			(end -0.7874 -0.4064)
			(stroke
				(width 0.1524)
				(type default)
			)
			(layer "F.SilkS")
		)
		(fp_line
			(start -0.7874 -0.4064)
			(end 0.7874 -0.4064)
			(stroke
				(width 0.1524)
				(type default)
			)
			(layer "F.SilkS")
		)
		(fp_line
			(start 0.67945 0.3048)
			(end 0.120396 0.3048)
			(stroke
				(width 0.1)
				(type default)
			)
			(layer "F.Fab")
		)
		(fp_line
			(start 0.67945 -0.3048)
			(end 0.67945 0.3048)
			(stroke
				(width 0.1)
				(type default)
			)
			(layer "F.Fab")
		)
		(fp_line
			(start 0.12065 -0.2794)
			(end 0.12065 -0.3048)
			(stroke
				(width 0.1)
				(type default)
			)
			(layer "F.Fab")
		)
		(fp_line
			(start 0.12065 -0.3048)
			(end 0.67945 -0.3048)
			(stroke
				(width 0.1)
				(type default)
			)
			(layer "F.Fab")
		)
		(fp_line
			(start 0.120396 0.3048)
			(end 0.120396 0.2794)
			(stroke
				(width 0.1)
				(type default)
			)
			(layer "F.Fab")
		)
		(fp_line
			(start 0.120396 0.2794)
			(end -0.12065 0.2794)
			(stroke
				(width 0.1)
				(type default)
			)
			(layer "F.Fab")
		)
		(fp_line
			(start -0.12065 0.3048)
			(end -0.67945 0.3048)
			(stroke
				(width 0.1)
				(type default)
			)
			(layer "F.Fab")
		)
		(fp_line
			(start -0.12065 0.2794)
			(end -0.12065 0.3048)
			(stroke
				(width 0.1)
				(type default)
			)
			(layer "F.Fab")
		)
		(fp_line
			(start -0.12065 -0.2794)
			(end 0.12065 -0.2794)
			(stroke
				(width 0.1)
				(type default)
			)
			(layer "F.Fab")
		)
		(fp_line
			(start -0.12065 -0.305054)
			(end -0.12065 -0.2794)
			(stroke
				(width 0.1)
				(type default)
			)
			(layer "F.Fab")
		)
		(fp_line
			(start -0.67945 0.3048)
			(end -0.67945 -0.305054)
			(stroke
				(width 0.1)
				(type default)
			)
			(layer "F.Fab")
		)
		(fp_line
			(start -0.67945 -0.305054)
			(end -0.12065 -0.305054)
			(stroke
				(width 0.1)
				(type default)
			)
			(layer "F.Fab")
		)
		(pad "1" smd circle
			(at -0.40005 0 180)
			(size 0 0)
			(layers "F.Cu" "F.Mask" "F.Paste")
			(net "P5V_AUX")
		)
		(pad "2" smd circle
			(at 0.40005 0 180)
			(size 0 0)
			(layers "F.Cu" "F.Mask" "F.Paste")
			(net "PVDDCR_CPU0_P1_VMON")
		)
	)
	(footprint ""
		(layer "F.Cu")
		(at 439.072782 -439.12536 -90)
		(property "Reference" "R4160"
			(at 0 0 270)
			(layer "F.SilkS")
			(hide yes)
			(effects
				(font
					(size 1.27 1.27)
				)
			)
		)
		(property "Value" ""
			(at 0 0 270)
			(layer "F.Fab")
			(effects
				(font
					(size 1.27 1.27)
				)
			)
		)
		(duplicate_pad_numbers_are_jumpers no)
		(fp_line
			(start -0.7874 0.4064)
			(end -0.7874 -0.4064)
			(stroke
				(width 0.1524)
				(type default)
			)
			(layer "F.SilkS")
		)
		(fp_line
			(start 0.7874 0.4064)
			(end -0.7874 0.4064)
			(stroke
				(width 0.1524)
				(type default)
			)
			(layer "F.SilkS")
		)
		(fp_line
			(start -0.7874 -0.4064)
			(end 0.7874 -0.4064)
			(stroke
				(width 0.1524)
				(type default)
			)
			(layer "F.SilkS")
		)
		(fp_line
			(start 0.7874 -0.4064)
			(end 0.7874 0.4064)
			(stroke
				(width 0.1524)
				(type default)
			)
			(layer "F.SilkS")
		)
		(fp_line
			(start -0.67945 0.3048)
			(end -0.67945 -0.305054)
			(stroke
				(width 0.1)
				(type default)
			)
			(layer "F.Fab")
		)
		(fp_line
			(start -0.12065 0.3048)
			(end -0.67945 0.3048)
			(stroke
				(width 0.1)
				(type default)
			)
			(layer "F.Fab")
		)
		(fp_line
			(start 0.120396 0.3048)
			(end 0.120396 0.2794)
			(stroke
				(width 0.1)
				(type default)
			)
			(layer "F.Fab")
		)
		(fp_line
			(start 0.67945 0.3048)
			(end 0.120396 0.3048)
			(stroke
				(width 0.1)
				(type default)
			)
			(layer "F.Fab")
		)
		(fp_line
			(start -0.12065 0.2794)
			(end -0.12065 0.3048)
			(stroke
				(width 0.1)
				(type default)
			)
			(layer "F.Fab")
		)
		(fp_line
			(start 0.120396 0.2794)
			(end -0.12065 0.2794)
			(stroke
				(width 0.1)
				(type default)
			)
			(layer "F.Fab")
		)
		(fp_line
			(start -0.12065 -0.2794)
			(end 0.12065 -0.2794)
			(stroke
				(width 0.1)
				(type default)
			)
			(layer "F.Fab")
		)
		(fp_line
			(start 0.12065 -0.2794)
			(end 0.12065 -0.3048)
			(stroke
				(width 0.1)
				(type default)
			)
			(layer "F.Fab")
		)
		(fp_line
			(start 0.12065 -0.3048)
			(end 0.67945 -0.3048)
			(stroke
				(width 0.1)
				(type default)
			)
			(layer "F.Fab")
		)
		(fp_line
			(start 0.67945 -0.3048)
			(end 0.67945 0.3048)
			(stroke
				(width 0.1)
				(type default)
			)
			(layer "F.Fab")
		)
		(fp_line
			(start -0.67945 -0.305054)
			(end -0.12065 -0.305054)
			(stroke
				(width 0.1)
				(type default)
			)
			(layer "F.Fab")
		)
		(fp_line
			(start -0.12065 -0.305054)
			(end -0.12065 -0.2794)
			(stroke
				(width 0.1)
				(type default)
			)
			(layer "F.Fab")
		)
		(pad "1" smd circle
			(at -0.40005 0 270)
			(size 0 0)
			(layers "F.Cu" "F.Mask" "F.Paste")
			(net "P3V3_AUX")
		)
		(pad "2" smd circle
			(at 0.40005 0 270)
			(size 0 0)
			(layers "F.Cu" "F.Mask" "F.Paste")
			(net "GPU_3V3IO_RSVD4")
		)
	)
	(footprint ""
		(layer "F.Cu")
		(at 277.265892 -385.27736 90)
		(property "Reference" "PPQ9"
			(at -7.517384 -2.267712 0)
			(unlocked yes)
			(layer "F.SilkS")
			(effects
				(font
					(size 0.7874 0.5842)
					(thickness 0.1524)
				)
				(justify left)
			)
		)
		(property "Value" ""
			(at 0 0 90)
			(layer "F.Fab")
			(effects
				(font
					(size 1.27 1.27)
				)
			)
		)
		(duplicate_pad_numbers_are_jumpers no)
		(fp_line
			(start 2.350008 -2.649982)
			(end 2.350008 -2.4892)
			(stroke
				(width 0.1524)
				(type default)
			)
			(layer "F.SilkS")
		)
		(fp_line
			(start -2.350008 -2.649982)
			(end 2.350008 -2.649982)
			(stroke
				(width 0.1524)
				(type default)
			)
			(layer "F.SilkS")
		)
		(fp_line
			(start -2.350008 -2.4384)
			(end -2.350008 -2.649982)
			(stroke
				(width 0.1524)
				(type default)
			)
			(layer "F.SilkS")
		)
		(fp_line
			(start 2.350008 2.4892)
			(end 2.350008 2.649982)
			(stroke
				(width 0.1524)
				(type default)
			)
			(layer "F.SilkS")
		)
		(fp_line
			(start 2.350008 2.649982)
			(end -2.350008 2.649982)
			(stroke
				(width 0.1524)
				(type default)
			)
			(layer "F.SilkS")
		)
		(fp_line
			(start -2.350008 2.649982)
			(end -2.350008 2.413)
			(stroke
				(width 0.1524)
				(type default)
			)
			(layer "F.SilkS")
		)
		(fp_poly
			(pts
				(xy -3.440938 -3.44805) (xy -2.640838 -3.440176) (xy -3.070098 -2.40284)
			)
			(stroke
				(width 0)
				(type default)
			)
			(fill yes)
			(layer "F.SilkS")
		)
		(fp_line
			(start 2.350008 -2.649982)
			(end 2.350008 2.649982)
			(stroke
				(width 0.1)
				(type default)
			)
			(layer "F.Fab")
		)
		(fp_line
			(start -2.350008 -2.649982)
			(end 2.350008 -2.649982)
			(stroke
				(width 0.1)
				(type default)
			)
			(layer "F.Fab")
		)
		(fp_line
			(start 2.350008 2.649982)
			(end -2.350008 2.649982)
			(stroke
				(width 0.1)
				(type default)
			)
			(layer "F.Fab")
		)
		(fp_line
			(start -2.350008 2.649982)
			(end -2.350008 -2.649982)
			(stroke
				(width 0.1)
				(type default)
			)
			(layer "F.Fab")
		)
		(fp_poly
			(pts
				(xy -3.717544 -1.905) (xy -4.758944 -2.3241) (xy -4.758944 -1.524)
			)
			(stroke
				(width 0)
				(type default)
			)
			(fill yes)
			(layer "F.Fab")
		)
		(pad "1" smd rect
			(at -2.999994 -1.905)
			(size 0.7112 1.1684)
			(layers "F.Cu" "F.Mask" "F.Paste")
			(net "P12V_AUX")
		)
		(pad "2" smd rect
			(at -2.999994 -0.635)
			(size 0.7112 1.1684)
			(layers "F.Cu" "F.Mask" "F.Paste")
			(net "P12V_AUX")
		)
		(pad "3" smd rect
			(at -2.999994 0.635)
			(size 0.7112 1.1684)
			(layers "F.Cu" "F.Mask" "F.Paste")
			(net "P12V_AUX")
		)
		(pad "4" smd rect
			(at -2.999994 1.905)
			(size 0.7112 1.1684)
			(layers "F.Cu" "F.Mask" "F.Paste")
			(net "MB0_CM_GATE_G0")
		)
		(pad "5" smd circle
			(at 0.925068 0)
			(size 0 0)
			(layers "F.Cu" "F.Mask" "F.Paste")
			(net "P12V_MAIN_R_0")
		)
		(zone
			(layer "F.Cu")
			(hatch none 0.5)
			(connect_pads
				(clearance 0)
			)
			(min_thickness 0.25)
			(keepout
				(tracks not_allowed)
				(vias allowed)
				(pads allowed)
				(copperpour not_allowed)
				(footprints allowed)
			)
			(placement
				(enabled no)
				(sheetname "")
			)
			(fill
				(thermal_gap 0.5)
				(thermal_bridge_width 0.5)
				(island_removal_mode 0)
			)
			(polygon
				(pts
					(xy 274.624292 -383.7178) (xy 279.907492 -383.7178) (xy 279.907492 -382.92786) (xy 274.624292 -382.92786)
				)
			)
		)
	)
	(footprint ""
		(layer "F.Cu")
		(at 101.035358 -344.796872 90)
		(property "Reference" "PC136_6"
			(at 0 0 90)
			(layer "F.SilkS")
			(hide yes)
			(effects
				(font
					(size 1.27 1.27)
				)
			)
		)
		(property "Value" ""
			(at 0 0 90)
			(layer "F.Fab")
			(effects
				(font
					(size 1.27 1.27)
				)
			)
		)
		(duplicate_pad_numbers_are_jumpers no)
		(fp_line
			(start 0.7874 -0.4064)
			(end 0.7874 0.4064)
			(stroke
				(width 0.1524)
				(type default)
			)
			(layer "F.SilkS")
		)
		(fp_line
			(start -0.7874 -0.4064)
			(end 0.7874 -0.4064)
			(stroke
				(width 0.1524)
				(type default)
			)
			(layer "F.SilkS")
		)
		(fp_line
			(start 0.7874 0.4064)
			(end -0.7874 0.4064)
			(stroke
				(width 0.1524)
				(type default)
			)
			(layer "F.SilkS")
		)
		(fp_line
			(start -0.7874 0.4064)
			(end -0.7874 -0.4064)
			(stroke
				(width 0.1524)
				(type default)
			)
			(layer "F.SilkS")
		)
		(fp_line
			(start -0.12065 -0.305054)
			(end -0.12065 -0.2794)
			(stroke
				(width 0.1)
				(type default)
			)
			(layer "F.Fab")
		)
		(fp_line
			(start -0.67945 -0.305054)
			(end -0.12065 -0.305054)
			(stroke
				(width 0.1)
				(type default)
			)
			(layer "F.Fab")
		)
		(fp_line
			(start 0.67945 -0.3048)
			(end 0.67945 0.3048)
			(stroke
				(width 0.1)
				(type default)
			)
			(layer "F.Fab")
		)
		(fp_line
			(start 0.12065 -0.3048)
			(end 0.67945 -0.3048)
			(stroke
				(width 0.1)
				(type default)
			)
			(layer "F.Fab")
		)
		(fp_line
			(start 0.12065 -0.2794)
			(end 0.12065 -0.3048)
			(stroke
				(width 0.1)
				(type default)
			)
			(layer "F.Fab")
		)
		(fp_line
			(start -0.12065 -0.2794)
			(end 0.12065 -0.2794)
			(stroke
				(width 0.1)
				(type default)
			)
			(layer "F.Fab")
		)
		(fp_line
			(start 0.120396 0.2794)
			(end -0.12065 0.2794)
			(stroke
				(width 0.1)
				(type default)
			)
			(layer "F.Fab")
		)
		(fp_line
			(start -0.12065 0.2794)
			(end -0.12065 0.3048)
			(stroke
				(width 0.1)
				(type default)
			)
			(layer "F.Fab")
		)
		(fp_line
			(start 0.67945 0.3048)
			(end 0.120396 0.3048)
			(stroke
				(width 0.1)
				(type default)
			)
			(layer "F.Fab")
		)
		(fp_line
			(start 0.120396 0.3048)
			(end 0.120396 0.2794)
			(stroke
				(width 0.1)
				(type default)
			)
			(layer "F.Fab")
		)
		(fp_line
			(start -0.12065 0.3048)
			(end -0.67945 0.3048)
			(stroke
				(width 0.1)
				(type default)
			)
			(layer "F.Fab")
		)
		(fp_line
			(start -0.67945 0.3048)
			(end -0.67945 -0.305054)
			(stroke
				(width 0.1)
				(type default)
			)
			(layer "F.Fab")
		)
		(pad "1" smd circle
			(at -0.40005 0 90)
			(size 0 0)
			(layers "F.Cu" "F.Mask" "F.Paste")
			(net "PVDDCR_CPU1_P1_VCCS")
		)
		(pad "2" smd circle
			(at 0.40005 0 90)
			(size 0 0)
			(layers "F.Cu" "F.Mask" "F.Paste")
			(net "GND")
		)
	)
	(footprint ""
		(layer "F.Cu")
		(at 289.136074 -397.85163 -90)
		(property "Reference" "R1210"
			(at 0 0 270)
			(layer "F.SilkS")
			(hide yes)
			(effects
				(font
					(size 1.27 1.27)
				)
			)
		)
		(property "Value" ""
			(at 0 0 270)
			(layer "F.Fab")
			(effects
				(font
					(size 1.27 1.27)
				)
			)
		)
		(duplicate_pad_numbers_are_jumpers no)
		(fp_line
			(start -0.32512 0.175006)
			(end -0.32512 -0.175006)
			(stroke
				(width 0.1)
				(type default)
			)
			(layer "F.Fab")
		)
		(fp_line
			(start 0.32512 0.175006)
			(end -0.32512 0.175006)
			(stroke
				(width 0.1)
				(type default)
			)
			(layer "F.Fab")
		)
		(fp_line
			(start -0.32512 -0.175006)
			(end 0.32512 -0.175006)
			(stroke
				(width 0.1)
				(type default)
			)
			(layer "F.Fab")
		)
		(fp_line
			(start 0.32512 -0.175006)
			(end 0.32512 0.175006)
			(stroke
				(width 0.1)
				(type default)
			)
			(layer "F.Fab")
		)
		(pad "1" smd rect
			(at -0.2667 0 270)
			(size 0.3048 0.381)
			(layers "F.Cu" "F.Mask" "F.Paste")
			(net "RST_SMB_RT_ROM_R1_N")
		)
		(pad "2" smd rect
			(at 0.2667 0 90)
			(size 0.3048 0.381)
			(layers "F.Cu" "F.Mask" "F.Paste")
			(net "FM_SMB_RT_ROM_MUX6_SEL")
		)
	)
	(footprint ""
		(layer "F.Cu")
		(at 324.168262 -404.0124 -90)
		(property "Reference" "R953"
			(at 0 0 270)
			(layer "F.SilkS")
			(hide yes)
			(effects
				(font
					(size 1.27 1.27)
				)
			)
		)
		(property "Value" ""
			(at 0 0 270)
			(layer "F.Fab")
			(effects
				(font
					(size 1.27 1.27)
				)
			)
		)
		(duplicate_pad_numbers_are_jumpers no)
		(fp_line
			(start -0.32512 0.175006)
			(end -0.32512 -0.175006)
			(stroke
				(width 0.1)
				(type default)
			)
			(layer "F.Fab")
		)
		(fp_line
			(start 0.32512 0.175006)
			(end -0.32512 0.175006)
			(stroke
				(width 0.1)
				(type default)
			)
			(layer "F.Fab")
		)
		(fp_line
			(start -0.32512 -0.175006)
			(end 0.32512 -0.175006)
			(stroke
				(width 0.1)
				(type default)
			)
			(layer "F.Fab")
		)
		(fp_line
			(start 0.32512 -0.175006)
			(end 0.32512 0.175006)
			(stroke
				(width 0.1)
				(type default)
			)
			(layer "F.Fab")
		)
		(pad "1" smd rect
			(at -0.2667 0 270)
			(size 0.3048 0.381)
			(layers "F.Cu" "F.Mask" "F.Paste")
			(net "RST_RT_CPU0_P0_PERST_N")
		)
		(pad "2" smd rect
			(at 0.2667 0 90)
			(size 0.3048 0.381)
			(layers "F.Cu" "F.Mask" "F.Paste")
			(net "RST_RT_CPU0_P0_PERST_R_N")
		)
	)
	(footprint ""
		(layer "F.Cu")
		(at 390.513316 -22.789134 90)
		(property "Reference" "R46"
			(at 0 0 90)
			(layer "F.SilkS")
			(hide yes)
			(effects
				(font
					(size 1.27 1.27)
				)
			)
		)
		(property "Value" ""
			(at 0 0 90)
			(layer "F.Fab")
			(effects
				(font
					(size 1.27 1.27)
				)
			)
		)
		(duplicate_pad_numbers_are_jumpers no)
		(fp_line
			(start 0.7874 0.011684)
			(end 0.7874 0.4064)
			(stroke
				(width 0.1524)
				(type default)
			)
			(layer "F.SilkS")
		)
		(fp_line
			(start 0.7874 0.4064)
			(end -0.7874 0.4064)
			(stroke
				(width 0.1524)
				(type default)
			)
			(layer "F.SilkS")
		)
		(fp_line
			(start -0.7874 0.4064)
			(end -0.7874 0.011684)
			(stroke
				(width 0.1524)
				(type default)
			)
			(layer "F.SilkS")
		)
		(fp_line
			(start -0.12065 -0.305054)
			(end -0.12065 -0.2794)
			(stroke
				(width 0.1)
				(type default)
			)
			(layer "F.Fab")
		)
		(fp_line
			(start -0.67945 -0.305054)
			(end -0.12065 -0.305054)
			(stroke
				(width 0.1)
				(type default)
			)
			(layer "F.Fab")
		)
		(fp_line
			(start 0.67945 -0.3048)
			(end 0.67945 0.3048)
			(stroke
				(width 0.1)
				(type default)
			)
			(layer "F.Fab")
		)
		(fp_line
			(start 0.12065 -0.3048)
			(end 0.67945 -0.3048)
			(stroke
				(width 0.1)
				(type default)
			)
			(layer "F.Fab")
		)
		(fp_line
			(start 0.12065 -0.2794)
			(end 0.12065 -0.3048)
			(stroke
				(width 0.1)
				(type default)
			)
			(layer "F.Fab")
		)
		(fp_line
			(start -0.12065 -0.2794)
			(end 0.12065 -0.2794)
			(stroke
				(width 0.1)
				(type default)
			)
			(layer "F.Fab")
		)
		(fp_line
			(start 0.120396 0.2794)
			(end -0.12065 0.2794)
			(stroke
				(width 0.1)
				(type default)
			)
			(layer "F.Fab")
		)
		(fp_line
			(start -0.12065 0.2794)
			(end -0.12065 0.3048)
			(stroke
				(width 0.1)
				(type default)
			)
			(layer "F.Fab")
		)
		(fp_line
			(start 0.67945 0.3048)
			(end 0.120396 0.3048)
			(stroke
				(width 0.1)
				(type default)
			)
			(layer "F.Fab")
		)
		(fp_line
			(start 0.120396 0.3048)
			(end 0.120396 0.2794)
			(stroke
				(width 0.1)
				(type default)
			)
			(layer "F.Fab")
		)
		(fp_line
			(start -0.12065 0.3048)
			(end -0.67945 0.3048)
			(stroke
				(width 0.1)
				(type default)
			)
			(layer "F.Fab")
		)
		(fp_line
			(start -0.67945 0.3048)
			(end -0.67945 -0.305054)
			(stroke
				(width 0.1)
				(type default)
			)
			(layer "F.Fab")
		)
		(pad "1" smd circle
			(at -0.40005 0 90)
			(size 0 0)
			(layers "F.Cu" "F.Mask" "F.Paste")
			(net "USB2_P11_DP")
		)
		(pad "2" smd circle
			(at 0.40005 0 90)
			(size 0 0)
			(layers "F.Cu" "F.Mask" "F.Paste")
			(net "USB2_CPU0_P11_DP")
		)
	)
)
